# T6G (Grand Teton) — schematic netlist excerpt (pin names and nets, part order shuffled) for the footprints in the layout excerpt that follows; sources: Cadence DE-HDL packaged netlist, KiCad conversion of 04192023_DAF0TMB3IC0_F0TG_MB_C_brd_V02_OCP.brd

C702  Q_CAP_DIFFBUS  DIFF BUS_0.22UF 6.3V 20% X6S  pkg C0201  page 67 : \1\ = P5E_CPU1_G1_TX_C_DN<3> ; \2\ = P5E_CPU1_G1_TX_DN<3>
PC315  Q_CAP  560PF 50V 10% EMPTY  pkg C0402  page 225 : A = SW_PVDD11_S3_P1_SW1 ; B = SW_PVDD11_S3_P1_SW1_RC
PC625_4  Q_CAP  1UF 25V 10% X6S  pkg C0402  page 223 : A = SW_P12V_AUX_PVDDIO_P1_FLT ; B = GND

(kicad_pcb
	(version 20260206)
	(generator "pcbnew")
	(generator_version "10.0")
	(general
		(thickness 1.6)
		(legacy_teardrops no)
	)
	(paper "A4")
	(title_block
		(title "04192023_DAF0TMB3IC0_F0TG_MB_C_brd_V02_OCP.brd")
		(comment 1 "Grand Teton / footprints 340-342 of 8354")
	)
	(layers
		(0 "F.Cu" signal "TOP")
		(4 "In1.Cu" signal "GND")
		(6 "In2.Cu" signal "IN1")
		(8 "In3.Cu" signal "GND1")
		(10 "In4.Cu" signal "IN2")
		(12 "In5.Cu" signal "GND2")
		(14 "In6.Cu" signal "IN3")
		(16 "In7.Cu" signal "GND3")
		(18 "In8.Cu" signal "VCC")
		(20 "In9.Cu" signal "VCC1")
		(22 "In10.Cu" signal "GND4")
		(24 "In11.Cu" signal "IN4")
		(26 "In12.Cu" signal "GND5")
		(28 "In13.Cu" signal "IN5")
		(30 "In14.Cu" signal "GND6")
		(32 "In15.Cu" signal "IN6")
		(34 "In16.Cu" signal "GND7")
		(2 "B.Cu" signal "BOTTOM")
		(9 "F.Adhes" user "F.Adhesive")
		(11 "B.Adhes" user "B.Adhesive")
		(13 "F.Paste" user "Package Geometry/Pastemask Top")
		(15 "B.Paste" user "Package Geometry/Pastemask Bottom")
		(5 "F.SilkS" user "Ref Des/Silkscreen Top")
		(7 "B.SilkS" user "Ref Des/Silkscreen Bottom")
		(1 "F.Mask" user "Board Geometry/Soldermask Top")
		(3 "B.Mask" user "Board Geometry/Soldermask Bottom")
		(17 "Dwgs.User" user "User.Drawings")
		(19 "Cmts.User" user "User.Comments")
		(21 "Eco1.User" user "User.Eco1")
		(23 "Eco2.User" user "User.Eco2")
		(25 "Edge.Cuts" user "Board Geometry/Outline")
		(27 "Margin" user)
		(31 "F.CrtYd" user "Package Geometry/Place Bound Top")
		(29 "B.CrtYd" user "Package Geometry/Place Bound Bottom")
		(35 "F.Fab" user "Ref Des/Assembly Top")
		(33 "B.Fab" user "Ref Des/Assembly Bottom")
	)
	(footprint ""
		(layer "F.Cu")
		(at 32.23514 -346.87129 -90)
		(property "Reference" "PC625_4"
			(at 0 0 270)
			(layer "F.SilkS")
			(hide yes)
			(effects
				(font
					(size 1.27 1.27)
				)
			)
		)
		(property "Value" ""
			(at 0 0 270)
			(layer "F.Fab")
			(effects
				(font
					(size 1.27 1.27)
				)
			)
		)
		(duplicate_pad_numbers_are_jumpers no)
		(fp_line
			(start -0.7874 0.4064)
			(end -0.7874 -0.4064)
			(stroke
				(width 0.1524)
				(type default)
			)
			(layer "F.SilkS")
		)
		(fp_line
			(start 0.7874 0.4064)
			(end -0.7874 0.4064)
			(stroke
				(width 0.1524)
				(type default)
			)
			(layer "F.SilkS")
		)
		(fp_line
			(start -0.7874 -0.4064)
			(end 0.7874 -0.4064)
			(stroke
				(width 0.1524)
				(type default)
			)
			(layer "F.SilkS")
		)
		(fp_line
			(start 0.7874 -0.4064)
			(end 0.7874 0.4064)
			(stroke
				(width 0.1524)
				(type default)
			)
			(layer "F.SilkS")
		)
		(fp_line
			(start -0.67945 0.3048)
			(end -0.67945 -0.305054)
			(stroke
				(width 0.1)
				(type default)
			)
			(layer "F.Fab")
		)
		(fp_line
			(start -0.12065 0.3048)
			(end -0.67945 0.3048)
			(stroke
				(width 0.1)
				(type default)
			)
			(layer "F.Fab")
		)
		(fp_line
			(start 0.120396 0.3048)
			(end 0.120396 0.2794)
			(stroke
				(width 0.1)
				(type default)
			)
			(layer "F.Fab")
		)
		(fp_line
			(start 0.67945 0.3048)
			(end 0.120396 0.3048)
			(stroke
				(width 0.1)
				(type default)
			)
			(layer "F.Fab")
		)
		(fp_line
			(start -0.12065 0.2794)
			(end -0.12065 0.3048)
			(stroke
				(width 0.1)
				(type default)
			)
			(layer "F.Fab")
		)
		(fp_line
			(start 0.120396 0.2794)
			(end -0.12065 0.2794)
			(stroke
				(width 0.1)
				(type default)
			)
			(layer "F.Fab")
		)
		(fp_line
			(start -0.12065 -0.2794)
			(end 0.12065 -0.2794)
			(stroke
				(width 0.1)
				(type default)
			)
			(layer "F.Fab")
		)
		(fp_line
			(start 0.12065 -0.2794)
			(end 0.12065 -0.3048)
			(stroke
				(width 0.1)
				(type default)
			)
			(layer "F.Fab")
		)
		(fp_line
			(start 0.12065 -0.3048)
			(end 0.67945 -0.3048)
			(stroke
				(width 0.1)
				(type default)
			)
			(layer "F.Fab")
		)
		(fp_line
			(start 0.67945 -0.3048)
			(end 0.67945 0.3048)
			(stroke
				(width 0.1)
				(type default)
			)
			(layer "F.Fab")
		)
		(fp_line
			(start -0.67945 -0.305054)
			(end -0.12065 -0.305054)
			(stroke
				(width 0.1)
				(type default)
			)
			(layer "F.Fab")
		)
		(fp_line
			(start -0.12065 -0.305054)
			(end -0.12065 -0.2794)
			(stroke
				(width 0.1)
				(type default)
			)
			(layer "F.Fab")
		)
		(pad "1" smd circle
			(at -0.40005 0 270)
			(size 0 0)
			(layers "F.Cu" "F.Mask" "F.Paste")
			(net "SW_P12V_AUX_PVDDIO_P1_FLT")
		)
		(pad "2" smd circle
			(at 0.40005 0 270)
			(size 0 0)
			(layers "F.Cu" "F.Mask" "F.Paste")
			(net "GND")
		)
	)
	(footprint ""
		(layer "F.Cu")
		(at 49.342294 -16.099536 90)
		(property "Reference" "C702"
			(at 0 0 90)
			(layer "F.SilkS")
			(hide yes)
			(effects
				(font
					(size 1.27 1.27)
				)
			)
		)
		(property "Value" ""
			(at 0 0 90)
			(layer "F.Fab")
			(effects
				(font
					(size 1.27 1.27)
				)
			)
		)
		(duplicate_pad_numbers_are_jumpers no)
		(fp_line
			(start 0.299974 -0.150114)
			(end 0.299974 0.150114)
			(stroke
				(width 0.1)
				(type default)
			)
			(layer "F.Fab")
		)
		(fp_line
			(start -0.299974 -0.150114)
			(end 0.299974 -0.150114)
			(stroke
				(width 0.1)
				(type default)
			)
			(layer "F.Fab")
		)
		(fp_line
			(start 0.299974 0.150114)
			(end -0.299974 0.150114)
			(stroke
				(width 0.1)
				(type default)
			)
			(layer "F.Fab")
		)
		(fp_line
			(start -0.299974 0.150114)
			(end -0.299974 -0.150114)
			(stroke
				(width 0.1)
				(type default)
			)
			(layer "F.Fab")
		)
		(pad "1" smd rect
			(at -0.2667 0 90)
			(size 0.3048 0.381)
			(layers "F.Cu" "F.Mask" "F.Paste")
			(net "P5E_CPU1_G1_TX_C_DN<3>")
		)
		(pad "2" smd rect
			(at 0.2667 0 90)
			(size 0.3048 0.381)
			(layers "F.Cu" "F.Mask" "F.Paste")
			(net "P5E_CPU1_G1_TX_DN<3>")
		)
	)
	(footprint ""
		(layer "F.Cu")
		(at 179.225956 -348.29115 180)
		(property "Reference" "PC315"
			(at 0 0 180)
			(layer "F.SilkS")
			(hide yes)
			(effects
				(font
					(size 1.27 1.27)
				)
			)
		)
		(property "Value" ""
			(at 0 0 180)
			(layer "F.Fab")
			(effects
				(font
					(size 1.27 1.27)
				)
			)
		)
		(duplicate_pad_numbers_are_jumpers no)
		(fp_line
			(start 0.7874 0.4064)
			(end -0.7874 0.4064)
			(stroke
				(width 0.1524)
				(type default)
			)
			(layer "F.SilkS")
		)
		(fp_line
			(start 0.7874 -0.4064)
			(end 0.7874 0.4064)
			(stroke
				(width 0.1524)
				(type default)
			)
			(layer "F.SilkS")
		)
		(fp_line
			(start -0.7874 0.4064)
			(end -0.7874 -0.4064)
			(stroke
				(width 0.1524)
				(type default)
			)
			(layer "F.SilkS")
		)
		(fp_line
			(start -0.7874 -0.4064)
			(end 0.7874 -0.4064)
			(stroke
				(width 0.1524)
				(type default)
			)
			(layer "F.SilkS")
		)
		(fp_line
			(start 0.67945 0.3048)
			(end 0.120396 0.3048)
			(stroke
				(width 0.1)
				(type default)
			)
			(layer "F.Fab")
		)
		(fp_line
			(start 0.67945 -0.3048)
			(end 0.67945 0.3048)
			(stroke
				(width 0.1)
				(type default)
			)
			(layer "F.Fab")
		)
		(fp_line
			(start 0.12065 -0.2794)
			(end 0.12065 -0.3048)
			(stroke
				(width 0.1)
				(type default)
			)
			(layer "F.Fab")
		)
		(fp_line
			(start 0.12065 -0.3048)
			(end 0.67945 -0.3048)
			(stroke
				(width 0.1)
				(type default)
			)
			(layer "F.Fab")
		)
		(fp_line
			(start 0.120396 0.3048)
			(end 0.120396 0.2794)
			(stroke
				(width 0.1)
				(type default)
			)
			(layer "F.Fab")
		)
		(fp_line
			(start 0.120396 0.2794)
			(end -0.12065 0.2794)
			(stroke
				(width 0.1)
				(type default)
			)
			(layer "F.Fab")
		)
		(fp_line
			(start -0.12065 0.3048)
			(end -0.67945 0.3048)
			(stroke
				(width 0.1)
				(type default)
			)
			(layer "F.Fab")
		)
		(fp_line
			(start -0.12065 0.2794)
			(end -0.12065 0.3048)
			(stroke
				(width 0.1)
				(type default)
			)
			(layer "F.Fab")
		)
		(fp_line
			(start -0.12065 -0.2794)
			(end 0.12065 -0.2794)
			(stroke
				(width 0.1)
				(type default)
			)
			(layer "F.Fab")
		)
		(fp_line
			(start -0.12065 -0.305054)
			(end -0.12065 -0.2794)
			(stroke
				(width 0.1)
				(type default)
			)
			(layer "F.Fab")
		)
		(fp_line
			(start -0.67945 0.3048)
			(end -0.67945 -0.305054)
			(stroke
				(width 0.1)
				(type default)
			)
			(layer "F.Fab")
		)
		(fp_line
			(start -0.67945 -0.305054)
			(end -0.12065 -0.305054)
			(stroke
				(width 0.1)
				(type default)
			)
			(layer "F.Fab")
		)
		(pad "1" smd circle
			(at -0.40005 0 180)
			(size 0 0)
			(layers "F.Cu" "F.Mask" "F.Paste")
			(net "SW_PVDD11_S3_P1_SW1")
		)
		(pad "2" smd circle
			(at 0.40005 0 180)
			(size 0 0)
			(layers "F.Cu" "F.Mask" "F.Paste")
			(net "SW_PVDD11_S3_P1_SW1_RC")
		)
	)
)
